CONCISE PART LIST - 1  
2D2R2F-GP_SMD-RG1-2D2R2F-GP,64A                          24      
3D01R5F-GP_SMD-RG5-3D01R5F-GP,A                          24      
74CBTLV1G125_SMLF-IC,C88177-00A C88177-001               7       
ADC128D818_SM-IC,H63642-001 H63642-001               1       
ADM1085_SMT-IC,H46130-001 H46130-001               1       
ADM1278_SM-IC,G99251-001 G99251-001               1       
ADM4073_SM-EMPTY,G12194-001 G12194-001               2       
ADM809_SMLF-IC,D23047-001-GND=A D23047-001               2       
AST1250_BGA-IC,G85138-002 G85138-002               1       
AT24C64_SOICLF-IC,C47049-001-GA C47049-001               1       
BATTERY_PLCLF-202168-001 202168-001               1       
CAPP_2626-270UF,16V,20%,OSCON,A A31228-047               9       
CAPP_3018-470UF,2.5V,20%,ALUM,A 699013-049               46      
CAPP_3018-470UF,6.3V,20%,POSCAA 724613-091               3       
CAPP_3018-68UF,16V,20%,TANT,72A 724613-112               16      
CAPP_4040LF-470UF,16V,20%,ALUMA A93539-036               4       
CAPP_7343-220UF,4V,20%,POSCAP,A 724613-067               4       
CAPP_7343HLF-330UF,10V,20%,POSA 724613-043               1       
CAPP_7343LF-330UF,6.3V,20%,POSA 724613-042               4       
CAPP_SM-470UF,2V,20%,ALUM,6990A 699013-031               8       
CAPTIVE_SCREW_TH-HDW,H57868-001 H57868-001               1       
CAP_0402-0.027UF,16V,10%,X7R,AA A36096-129               4       
CAP_0402-0.047UF,25V,10%,X7R,AA A36096-090               1       
CAP_0402-0.220UF,16V,10%,X7R,AA A36096-104               24      
CAP_0402-0.22UF,16V,10%,EMPTY,A A36096-155               16      
CAP_0402-0.22UF,16V,10%,X7R,A3A A36096-155               208     
CAP_0402-1.0UF,16V,10%,X6S,D97A D97712-011               70      
CAP_0402-1.0UF,16V,10%,X7S,G71A G71842-007               1       
CAP_0402LF-0.022UF,16V,10%,X7RA A36096-073               1       
CAP_0402LF-0.039UF,25V,10%,X7RA A36096-063               1       
CAP_0402LF-10.0PF,50V,5%,COG,AA A36094-025               1       
CAP_0402LF-100.0PF,50V,5%,COG,A A36095-026               8       
CAP_0402LF-1000PF,50V,10%,EMPTA A36096-046               13      
CAP_0402LF-1000PF,50V,10%,X7R,A A36096-046               55      
CAP_0402LF-12.0PF,50V,5%,COG,AA A36095-043               2       
CAP_0402LF-15.0PF,50V,5%,COG,AA A36095-047               2       
CAP_0402LF-18PF,50V,5%,C0G,A36A A36095-042               2       
CAP_0402LF-22.0PF,50V,5%,COG,AA A36095-030               2       
CAP_0402LF-2200PF,50V,10%,X7R,A A36096-075               9       
CAP_0402LF-220PF,50V,10%,X7R,AA A36096-050               20      
CAP_0402LF-27.0PF,50V,5%,COG,AA A36095-038               2       
CAP_0402LF-270PF,50V,10%,X7R,AA A36096-065               1       
CAP_0402LF-33.0PF,50V,5%,COG,AA A36095-031               2       
CAP_0402LF-3300PF,50V,10%,EMPTA A36096-091               5       
CAP_0402LF-47.0PF,50V,5%,COG,AA A36095-025               7       
CAP_0402LF-47.0PF,50V,5%,EMPTYA A36095-025               2       
CAP_0402LF-4700PF,50V,10%,EMPTA A36096-066               4       
CAP_0402LF-470PF,50V,10%,EMPTYA A36096-049               2       
CAP_0402LF-470PF,50V,10%,X7R,AA A36096-049               4       
CAP_0603-0.47UF,16V,10%,X7R,20A 202297-006               1       
CAP_0603-10UF,6.3V,20%,EMPTY,EA E15431-002               2       
CAP_0603-10UF,6.3V,20%,X6S,E15A E15431-002               22      
CAP_0603-4.7UF,6.3V,10%,X6S,E1A E15431-003               10      
CAP_0603LF-0.033UF,50V,10%,X7RA 603269-064               1       
CAP_0603LF-0.1UF,25V,10%,X7R,6A 602433-020               7       
CAP_0603LF-10UF,4V,20%,X6S,E15A E15431-001               89      
CAP_0805-100UF,4V,20%,X5R,6024A 602433-112               40      
CAP_0805-10UF,16V,10%,X6S,C953A C95333-007               108     
CAP_0805-10UF,16V,10%,X7R,G106A G10601-001               14      
CAP_0805-22UF,6.3V,20%,X6S,C95A C95333-008               9       
CAP_0805-47UF,4V,20%,X6S,C9533A C95333-006               109     
CAP_0805LF-22UF,4V,20%,X6S,C95A C95333-002               30      
CAP_1206-0.068UF,50V,20%,X7R,1A 108427-047               1       
CAP_1206LF-22UF,16V,10%,X6S,D3A D38464-005               3       
CAP_1210-100UF,16V,20%,X5R,644A 644066-127               7       
CAP_1210-47UF,16V,20%,EMPTY,D3A D38464-007               2       
CAP_1210-47UF,16V,20%,X6S,D384A D38464-007               12      
CAP_A_0402V-0.01UF,25V,10%,EMPA A36096-045               4       
CAP_A_0402V-0.01UF,25V,10%,X7RA A36096-045               112     
CAP_A_0402V-0.1UF,16V,10%,EMPTA A36096-030               17      
CAP_A_0402V-0.1UF,16V,10%,X7R,A A36096-030               294     
CAP_A_0402V-1.0UF,6.3V,10%,EMPA D97712-004               2       
CAP_A_0402V-1.0UF,6.3V,10%,X6SA D97712-004               149     
CAP_A_0603V-22.0UF,4V,20%,EMPTA E15431-004               2       
CAP_A_0603V-22.0UF,4V,20%,X6S,A E15431-004               391     
CAP_A_0603V-47UF,4V,20%,X5R,60A 602433-106               52      
CHOKE_4PIN_SMLF-90 OHM,EMPTY,7A 752402-015               1       
CHOKE_4PIN_SM_B-67 OHM,EMPTY,7A 752402-028               2       
CONN12_C73564003_PIP-CONN,C735A C73564-003               3       
CONN12_G98257001_THMT-CONN,G98A G98257-001               2       
CONN14_H54902001_PIP-CONN,H549A H54902-001               1       
CONN17_H71061002_PIP1-CONN,H71A H71061-002               1       
CONN36_G97614001_CP-CONN,G9761A G97614-001               1       
CONN3_C95678002_PIP-CONN,C9567A C95678-002               4       
CONN3_G98259001_PIP-CONN,G9825A G98259-001               1       
CONN4_D42317002_PIP-CONN,D4231A D42317-002               1       
CONN4_H73295001_PIP-CONN,H7329A H73295-001               1       
CONN4_H73295001_PIP-EMPTY,H732A H73295-001               1       
CONN6_C74770005_PIP-HDR,C74770A C74770-005               2       
CONN72_G97614002_A_CP-CONN,G97A G97614-002               1       
CONN76_H22707001_THMT1-CONN,H2A H22707-001               2       
CONN7_E82125014_PIP_TH-CONN,E8A E82125-014               1       
CONN7_E82125014_PIP_TH-EMPTY,EA E82125-014               1       
CONN8_C77962004_PIP-CONN,C7796A C77962-004               1       
CONN8_H62179001_PIP-CONN,H6217A H62179-001               1       
CONN9_H51826001_PIP2-CONN,H518A H51826-001               1       
CRYSTAL_2013-25.000MHZ,IC,D717A D71700-057               1       
CRYSTAL_2013-25.000MHZ,IC,H196A H19611-001               1       
CRYSTAL_2013-48.000MHZ,IC,D717A D71700-058               1       
CRYSTAL_2013LF-25.000MHZ,IC,D7B D71700-033               1       
CRYSTAL_SM-24.000MHZ,IC,D95126A D95126-001               1       
CRYSTAL_SM-32.768KHZ,IC,C13544A C13544-023               1       
CSD87384M_SM-IC,H66258-001 H66258-001               1       
DIODE2A_DUAL_SMLF-BAS70-05,DIOA C90169-001               1       
DIODEAC_DUAL_ARRAY_SM9-ESD3V3UA G18435-001               2       
DIODE_SM-1N4148W,IC,D89194-001 D89194-001               4       
DIODE_SM-MBRS340T3G,EMPTY,C819A C81983-002               1       
DIODE_SM-SDMK0340L,EMPTY,H7179A H71799-001               2       
DIODE_SM-SDMK0340L,IC,H71799-0A H71799-001               6       
DIODE_SMLF-1N5819HW,IC,D55839-A D55839-001               1       
DIODE_SMLF-BAT54WS,IC,C73510-0A C73510-001               4       
FERRITE_SM-120,FB,693286-027 693286-027               6       
FERRITE_SM-22,FB,656554-051 656554-051               6       
FERRITE_SMLF-30,FB,693286-021 693286-021               2       
FERRITE_SMLF-300,EMPTY,693286-A 693286-046               2       
FERRITE_SMLF-300,FB,693286-046 693286-046               3       
FERRITE_SMLF-60,FB,693286-001 693286-001               1       
FERRITE_SMLF-600,FB,656554-043 656554-043               2       
FET_N_DUAL_SMLF-2N7002DW,FET,DA D24280-001               3       
FET_N_DUAL_SMLF-NTJD4001N,FET,A E40049-001               15      
FET_N_SOT23-2N7002,FET,C79254-A C79254-001               6       
FET_N_SOT23LF-2N7002,FET,C7925A C79254-001               8       
FSA3357_SM-IC,C63273-001 C63273-001               2       
FUSE_SM-IC,C94311-016 C94311-016               1       
FUSE_SMLF-IC,C94311-006 C94311-006               1       
FUSE_SMT-IC,H45581-001 H45581-001               1       
GTL2014_SM-IC,D66151-001 D66151-001               6       
ICS9FGP204_MLFP-IC,E95226-001 E95226-001               1       
INDUCTOR_SM-0.12UH,IND,D92183-A D92183-034               18      
INDUCTOR_SM-0.3UH,IND,D92183-0A D92183-036               4       
INDUCTOR_SM-0.47UH,IND,E13358-A E13358-018               4       
INDUCTOR_SM-1.00UH,IND,E98679-A E98679-006               1       
INDUCTOR_SM-100NH,IND,D92183-0A D92183-019               2       
INDUCTOR_SM-100NH,IND,D92183-0B D92183-020               5       
INDUCTOR_SM-150NH,IND,D92183-0A D92183-021               2       
INDUCTOR_SM-2.2UH,IND,E98761-0A E98761-003               1       
INDUCTOR_SMT-0.022UH,IND,72189A 721891-082               1       
IR354XX_SM-IR35411,IC,H73688-0A H73688-001               18      
IR354XX_SM-IR35412,IC,H73684-0A H73684-001               6       
K4B1G16_BGA1-IC,G38649-001 G38649-001               1       
LBG_CORE_QAT_EXT_D_BGA1-IC,H91A H91415-002               1       
LCMXO2_A_256BGA-IC,H63395-001 H63395-001               1       
LED_1NC-BLUE,IC,C96565-012 C96565-012               1       
LED_1NCLF-GREEN,IC,C96565-011 C96565-011               1       
LED_1NCLF-YELLOW,IC,C96565-003 C96565-003               1       
LED_A1-RED,IC,D14725-005 D14725-005               1       
LED_A1LF-GREEN,IC,C97278-010 C97278-010               3       
LED_A1LF-GREEN,IC,D14725-022 D14725-022               2       
M25PE16_SM-IC,H77797-001 H77797-001               1       
MAX9634_SOT-IC,H35789-001 H35789-001               4       
MIC5166_DFN-IC,H55101-001 H55101-001               4       
MOSFETN_1D3S_SOT5-IC,G68777-001 G68777-001               3       
MOSFET_N_LCC3-BSZ019N03LS,NFETA G26762-001               4       
MTG_KEYHOLE_TH-EMPTY,NA NA                       7       
NB3W1200L_LCC-IC,H13585-001 H13585-001               1       
NC7SB3157_SMLF-IC,C99406-001 C99406-001               3       
NCP3232L_SM-IC,H86355-001 H86355-001               4       
NPN_DUAL_SSOPLF-MBT3904,EMPTY,A C52264-001               1       
NPN_DUAL_SSOPLF-MBT3904,XSTR,CA C52264-001               1       
NPN_SM-MMBT3904,IC,C52245-001 C52245-001               5       
OSC_C_6P10-156.25MHZ,OSC,G6383A G63831-004               2       
OSC_C_SM4-24MHZ,OSC,D34520-021 D34520-021               1       
PCA9517_SM-IC,G77073-001-GND=GA G77073-001               1       
PCA9617_SSOP-IC,G81764-001-GNDA G81764-001               4       
PI3B3257A_TSSOPLF-IC,E16801-001 E16801-001               2       
PI7C9X1172_QFN-IC,H66899-001 H66899-001               1       
PNP_TO92-MPS2907,IC,G73554-001 G73554-001               2       
PXE1110B_QFN-IC,H89187-001 H89187-001               3       
PXE1610B_QFN-IC,H79206-001 H79206-001               2       
PXM1310B_QFN-IC,H89186-001 H89186-001               4       
RCC_DFX1940_ID4-EMPTY,N_A N_A                      4       
RES_0402-0.0,5%,1/16W,CHIP,G21A G21497-005               269     
RES_0402-0.0,5%,1/16W,EMPTY,G2A G21497-005               92      
RES_0402-1.0,1%,1/16W,CHIP,G21A G21796-090               24      
RES_0402-1.00K,1%,1/16W,CHIP,GA G21796-026               140     
RES_0402-1.00K,1%,1/16W,EMPTY,A G21796-026               22      
RES_0402-1.0K,0.1%,1/16W,CHIP,A G85996-004               8       
RES_0402-1.0M,1%,1/16W,EMPTY,GA G21796-021               5       
RES_0402-1.37K,1%,1/16W,CHIP,GA G21796-095               3       
RES_0402-1.5K,1%,1/16W,CHIP,G2A G21796-003               12      
RES_0402-1.8K,1%,1/16W,CHIP,G2A G21796-336               8       
RES_0402-10.0,1%,1/16W,CHIP,G2A G21796-066               42      
RES_0402-10.0,1%,1/16W,EMPTY,GA G21796-066               2       
RES_0402-10.0K,1%,1/16W,CHIP,GA G21796-016               99      
RES_0402-10.0K,1%,1/16W,EMPTY,A G21796-016               14      
RES_0402-100.0,1%,1/16W,CHIP,GA G21796-017               53      
RES_0402-100.0,1%,1/16W,EMPTY,A G21796-017               10      
RES_0402-100.0K,1%,1/16W,CHIP,A G21796-010               27      
RES_0402-100.0K,1%,1/16W,CHIP,B G21796-160               9       
RES_0402-100.0K,1%,1/16W,EMPTYA G21796-010               10      
RES_0402-105.0K,1%,1/16W,CHIP,A G21796-099               1       
RES_0402-110,1%,1/16W,EMPTY,G2A G21796-203               1       
RES_0402-113,1%,1/16W,CHIP,G21A G21796-341               1       
RES_0402-11K,1%,1/16W,CHIP,G21A G21796-220               1       
RES_0402-12.1K,1%,1/16W,CHIP,GA G21796-089               1       
RES_0402-12K,1%,1/16W,CHIP,G21A G21796-264               1       
RES_0402-13K,1.0%,1/16W,CHIP,GA G21796-221               1       
RES_0402-15.0K,1%,1/16W,CHIP,GA G21796-107               2       
RES_0402-150.0,1%,1/16W,CHIP,GA G21796-009               38      
RES_0402-150.0K,1%,1/16W,CHIP,A G21796-109               2       
RES_0402-169,1.0%,1/16W,CHIP,GA G21796-276               1       
RES_0402-16K,1.0%,1/16W,CHIP,GA G21796-317               2       
RES_0402-2,1.0%,1/16W,CHIP,G21A G21796-274               12      
RES_0402-2.0K,1%,1/16W,CHIP,G2A G21796-001               14      
RES_0402-2.0K,1%,1/16W,EMPTY,GA G21796-001               2       
RES_0402-2.2,5%,1/16W,EMPTY,G2A G21497-016               5       
RES_0402-2.21K,1%,1/16W,CHIP,GA G21796-112               14      
RES_0402-2.26K,1.0%,1/16W,CHIPA G21796-311               7       
RES_0402-2.26K,1.0%,1/16W,EMPTA G21796-311               13      
RES_0402-2.67K,1%,1/16W,CHIP,GA G21796-180               1       
RES_0402-2.7K,1%,1/16W,CHIP,G2A G21796-344               8       
RES_0402-2.7K,1%,1/16W,EMPTY,GA G21796-344               5       
RES_0402-20.0,1%,1/16W,CHIP,G2A G21796-173               68      
RES_0402-20.0,1%,1/16W,EMPTY,GA G21796-173               4       
RES_0402-20.0K,1%,1/16W,CHIP,GA G21796-040               9       
RES_0402-20.0K,1%,1/16W,EMPTY,A G21796-040               1       
RES_0402-200.0,1%,1/16W,CHIP,GA G21796-004               11      
RES_0402-200.0K,1%,1/16W,CHIP,A G21796-080               1       
RES_0402-22.1,1.0%,1/16W,CHIP,A G21796-250               33      
RES_0402-221,1.0%,1/16W,CHIP,GA G21796-271               10      
RES_0402-23.2K,1%,1/16W,CHIP,GA G21796-114               1       
RES_0402-24.9K,1%,1/16W,CHIP,GA G21796-254               1       
RES_0402-240,1.0%,1/16W,CHIP,GA G21796-294               19      
RES_0402-240,1.0%,1/16W,EMPTY,A G21796-294               18      
RES_0402-249,0.1%,1/16W,CHIP,GA G85996-031               2       
RES_0402-249K,1.0%,1/16W,CHIP,A G21796-189               1       
RES_0402-27.4,1%,1/16W,CHIP,G2A G21796-182               24      
RES_0402-274K,1.0%,1/16W,CHIP,A G21796-331               1       
RES_0402-3.16K,1%,1/16W,CHIP,GA G21796-043               7       
RES_0402-3.32K,1%,1/16W,CHIP,GA G21796-027               4       
RES_0402-3.32K,1%,1/16W,EMPTY,A G21796-027               3       
RES_0402-3.3K,5%,1/16W,CHIP,G2A G21497-013               2       
RES_0402-3.48K,1.0%,1/16W,CHIPA G21796-279               2       
RES_0402-3.74K,1%,1/16W,CHIP,GA G21796-059               1       
RES_0402-301.0,1%,1/16W,CHIP,GA G21796-076               1       
RES_0402-33.0K,5%,1/16W,CHIP,GA G21497-023               1       
RES_0402-33.2,1%,1/16W,CHIP,G2A G21796-074               91      
RES_0402-33.2,1%,1/16W,EMPTY,GA G21796-074               1       
RES_0402-330,5%,1/16W,CHIP,G21A G21497-028               2       
RES_0402-348,1%,1/16W,CHIP,G21A G21796-340               1       
RES_0402-348,1%,1/16W,EMPTY,G2A G21796-340               1       
RES_0402-4.02K,1%,1/16W,CHIP,GA G21796-082               8       
RES_0402-4.75K,1%,1/16W,CHIP,GA G21796-072               118     
RES_0402-4.75K,1%,1/16W,EMPTY,A G21796-072               33      
RES_0402-4.99K,1%,1/16W,CHIP,GA G21796-013               2       
RES_0402-40.2K,1%,1/16W,CHIP,GA G21796-133               2       
RES_0402-42.2,1.0%,1/16W,EMPTYA G21796-259               24      
RES_0402-470.0,5%,1/16W,CHIP,GA G21497-024               1       
RES_0402-475.0,1%,1/16W,CHIP,GA G21796-077               2       
RES_0402-49.9,1%,1/16W,CHIP,G2A G21796-047               60      
RES_0402-49.9,1%,1/16W,EMPTY,GA G21796-047               5       
RES_0402-49.9K,1%,1/16W,CHIP,GA G21796-048               3       
RES_0402-5.11K,1%,1/16W,CHIP,GA G21796-140               6       
RES_0402-5.36K,1.0%,1/16W,CHIPA G21796-297               2       
RES_0402-5.76K,1%,1/16W,CHIP,GA G21796-143               1       
RES_0402-51,5.0%,1/16W,CHIP,G2A G21497-048               4       
RES_0402-51.1,1.0%,1/16W,CHIP,A G21796-208               11      
RES_0402-560,5%,1/16W,CHIP,G21A G21497-062               1       
RES_0402-6.19K,1%,1/16W,CHIP,GA G21796-161               2       
RES_0402-6.34K,1%,1/16W,CHIP,GA G21796-146               5       
RES_0402-63.4K,1.0%,1/16W,CHIPA G21796-327               1       
RES_0402-64.9,1.0%,1/16W,CHIP,A G21796-298               5       
RES_0402-64.9K,1%,1/16W,CHIP,GA G21796-148               1       
RES_0402-665,1.0%,1/16W,CHIP,GA G21796-235               18      
RES_0402-68.1K,1%,1/16W,EMPTY,A G21796-187               24      
RES_0402-69.8K,1%,1/16W,CHIP,GA G21796-007               1       
RES_0402-7.5K,1%,1/16W,CHIP,G2A G21796-177               1       
RES_0402-7.87K,1.0%,1/16W,CHIPA G21796-242               8       
RES_0402-75,1.0%,1/16W,CHIP,G2A G21796-267               6       
RES_0402-75K,1%,1/16W,CHIP,G21A G21796-224               1       
RES_0402-8.06K,1%,1/16W,CHIP,GA G21796-078               3       
RES_0402-8.2K,1%,1/16W,CHIP,G2A G21796-345               3       
RES_0402-8.2K,1%,1/16W,EMPTY,GA G21796-345               1       
RES_0402-90.9,1%,1/16W,CHIP,G2A G21796-365               8       
RES_0402-90.9K,1%,1/16W,CHIP,GA G21796-058               2       
RES_0603-0,5.0%,1/10W,CHIP,G22A G22178-002               3       
RES_0603-0,5.0%,1/10W,EMPTY,G2A G22178-002               1       
RES_0603-10.0,1%,1/10W,CHIP,G2A G22026-041               2       
RES_0603-100.0,1%,1/10W,CHIP,GA G22026-038               2       
RES_0603-100.0K,1%,1/10W,CHIP,A G22026-050               2       
RES_0603-10M,1.0%,1/10W,CHIP,GA G22026-112               1       
RES_0603-120.0,1%,1/10W,CHIP,GA G22026-003               8       
RES_0603-2.2,1.0%,1/10W,CHIP,GA G22026-127               5       
RES_0603-200K,0.1%,1/10W,CHIP,A G22369-010               1       
RES_0603-475.0,1%,1/10W,CHIP,GA G22026-030               1       
RES_0805-0.0,5%,1/8W,CHIP,G221A G22179-004               1       
RES_1206-0.002,1%,1W,CHIP,G521A G52199-004               4       
RES_2010-0.001,1%,1W,CHIP,E309A E30969-002               2       
RES_PWR_6PAD-0.001,1%,3W,CHIP,A E74391-005               2       
RT8240_QFN-IC,H66262-001 H66262-001               1       
RT9059_DFN-IC,H65765-001 H65765-001               3       
SC2K2P50V3KX-GP_SMD-BCG6-SC2K2A                          24      
SCONN10_C12536004_SMLF-CONN,C1A C12536-004               1       
SCONN11_H67026001_SM-CONN,H670A H67026-001               1       
SCONN120_A28699018_SM-SCONN,A2A A28699-018               1       
SCONN120_H61426002_SM-CONN,H61A H61426-002               4       
SCONN200_H68296001_SM-CONN,H68A H68296-001               1       
SCONN24_H46321001_SM-SCONN,H46A H46321-001               1       
SCONN288_H44441003_PIP-SCONN,HA H44441-003               12      
SCONN288_H44441004_PIP-SCONN,HA H44441-004               12      
SCONN3_D53458001_SM-EMPTY,D534A D53458-001               1       
SCONN60_C21100002_SMLF-CONN,C2A C21100-002               1       
SCONN64_H87568002_A_SMT-CONN,HA H87568-002               1       
SCONN75K_H17033002_SMT1-SCONN,A H17033-002               1       
SCONN80_E67482007_SM-CONN,E674A E67482-007               1       
SHUNT_SH0201-EMPTY,N_A N_A                      16      
SKX_EXT_B_BGA1-IC,TBD TBD                      2       
SLG55021_SM-IC,G56246-001 G56246-001               4       
SNLABEL_A_LABEL-EMPTY,N_A N_A                      5       
SOCKET_P_MECH_A_LEFT-P0,PLASTIA H37604-201               2       
SOCKET_P_MECH_A_RIGHT-P0,PLASTA H37604-101               2       
SPRINGVILLE_SM1-IC,G47144-004 G47144-004               1       
STANDOFF_TH1-SO,H72821-001 H72821-001               1       
SWITCH_D37771002_SM-IC,D37771-A D37771-002               1       
SWITCH_D90553001_SMLF-IC,D9055A D90553-001               1       
SW_H67881001_SM-IC,H67881-001 H67881-001               1       
TMP421_TSSOP-IC,G62962-001 G62962-001               2       
TPS2061_SM-IC,H66405-001 H66405-001               1       
TPS3700_SM-IC,H69492-001 H69492-001               4       
TPS54821_LCC-IC,H63269-001 H63269-001               1       
TTL08_QFN15-74LVC08A,IC,D90404B D90404-001               1       
TTL1G07_A_SOP-74LVC1G07,IC,C88B C88419-001               9       
TTL1G08_SOTLF-NC7SZ08,IC,D1032B D10321-001               3       
TTL1G08_SOTLF-NC7SZ08,IC,D1032C D10321-001               1       
TTL1G126_A_SOT-74HC1G126,IC,A7B A79322-001               5       
TTL1G32_A_SOT-74LVC1G32,IC,E60B E60229-001               2       
TTL1G86_SOTLF-74AHCT1G86,IC,D3B D39848-001               1       
TTL2G07_SOT23LF-74LVC2G07,IC,DB D22707-001               2       
TTL2G14_SMLF-74LVC2G14,IC,D184B D18476-001               3       
TTL3126_QFNLF-74CBTLV3126,IC,DB D18317-001               2       
VERT_BATT_3PIN_PIP-3PVERT,C686A C68619-005               1       
W25Q128_SKT16-IC,H12709-001 H12709-001               1       
W25Q256_XSOI-IC,H25002-001 H25002-001               2       
ZENER_SM-13V,IC,H69095-001 H69095-001               1       

Total                                     4236    
END CONCISE PART LIST
